FILE_TYPE = MACRO_DRAWING;
SET COLOR_WIRE YELLOW;
SET COLOR_PROP ORANGE;
SET COLOR_DOT WHITE;
SET COLOR_ARC YELLOW;
SET COLOR_BODY GREEN;
SET COLOR_NOTE PURPLE;
SET PROP_DISPLAY VALUE;
SET PAGE_NUMBER P244;
FORCEADD GND..1
(-8200 8675);
FORCEPROP 3 LASTPIN (-8200 8725) SIG_NAME GND\g
J 0
(-8190 8735);
DISPLAY 0.659574 (-8190 8735);
PAINT MONO (-8190 8735);
DISPLAY INVISIBLE (-8190 8735);
FORCEPROP 2 LAST CDS_LIB pure_quanta_power
J 0
(-8200 8675);
DISPLAY INVISIBLE (-8200 8675);
FORCEPROP 1 LAST SIZE 1B
J 0
(-8125 8625);
DISPLAY 0.872340 (-8125 8625);
PAINT AQUA (-8125 8625);
DISPLAY INVISIBLE (-8125 8625);
FORCEPROP 1 LAST HDL_POWER GND
J 0
(-8200 8825);
DISPLAY 0.872340 (-8200 8825);
PAINT GREEN (-8200 8825);
DISPLAY INVISIBLE (-8200 8825);
FORCEPROP 1 LAST PATH I1
J 0
(-8125 8675);
DISPLAY 0.872340 (-8125 8675);
PAINT AQUA (-8125 8675);
DISPLAY INVISIBLE (-8125 8675);
FORCEADD Q_CAP..1
(-7025 8900);
FORCEPROP 1 LAST LOCATION PC1850
J 0
(-6975 9000);
DISPLAY 0.617021 (-6975 9000);
PAINT AQUA (-6975 9000);
FORCEPROP 0 LAST $SEC 1
J 0
(-6975 9050);
DISPLAY 0.680851 (-6975 9050);
PAINT MONO (-6975 9050);
DISPLAY INVISIBLE (-6975 9050);
FORCEPROP 0 LAST CDS_SEC 1
J 0
(-6975 9050);
DISPLAY 1.021277 (-6975 9050);
DISPLAY INVISIBLE (-6975 9050);
FORCEPROP 1 LASTPIN (-7025 9000) $PN 1
J 0
(-7015 8980);
DISPLAY 0.617021 (-7015 8980);
PAINT MONO (-7015 8980);
FORCEPROP 1 LASTPIN (-7025 8800) $PN 2
J 0
(-7015 8780);
DISPLAY 0.617021 (-7015 8780);
PAINT MONO (-7015 8780);
FORCEPROP 1 LAST VALUE 22UF
J 0
(-6975 8950);
DISPLAY 0.617021 (-6975 8950);
PAINT SKYBLUE (-6975 8950);
FORCEPROP 1 LAST TOLERANCE 20%
J 0
(-6975 8850);
DISPLAY 0.617021 (-6975 8850);
PAINT SKYBLUE (-6975 8850);
FORCEPROP 1 LAST VOLTAGE 16V
J 0
(-6975 8900);
DISPLAY 0.617021 (-6975 8900);
PAINT SKYBLUE (-6975 8900);
FORCEPROP 1 LAST MATERIAL X6S
J 0
(-6975 8800);
DISPLAY 0.617021 (-6975 8800);
PAINT SKYBLUE (-6975 8800);
FORCEPROP 1 LAST PACK_TYPE C0805
J 0
(-6975 8700);
DISPLAY 0.617021 (-6975 8700);
PAINT SKYBLUE (-6975 8700);
FORCEPROP 2 LAST CDS_LIB pure_quanta
J 0
(-7025 8900);
DISPLAY INVISIBLE (-7025 8900);
FORCEPROP 1 LAST PATH I10
J 0
(-6975 9050);
DISPLAY 0.978723 (-6975 9050);
PAINT WHITE (-6975 9050);
DISPLAY INVISIBLE (-6975 9050);
FORCEPROP 1 LAST PART_NUMBER CH6223MEA01
J 0
(-6975 8750);
DISPLAY 0.617021 (-6975 8750);
PAINT BLUE (-6975 8750);
DISPLAY INVISIBLE (-6975 8750);
FORCEADD Q_CAP..1
(-6575 8900);
FORCEPROP 1 LAST LOCATION PC1898
J 0
(-6525 9000);
DISPLAY 0.617021 (-6525 9000);
PAINT AQUA (-6525 9000);
FORCEPROP 0 LAST $SEC 1
J 0
(-6525 9050);
DISPLAY 0.680851 (-6525 9050);
PAINT MONO (-6525 9050);
DISPLAY INVISIBLE (-6525 9050);
FORCEPROP 0 LAST CDS_SEC 1
J 0
(-6525 9050);
DISPLAY 0.680851 (-6525 9050);
DISPLAY INVISIBLE (-6525 9050);
FORCEPROP 1 LASTPIN (-6575 9000) $PN 1
J 0
(-6565 8980);
DISPLAY 0.617021 (-6565 8980);
PAINT MONO (-6565 8980);
FORCEPROP 1 LASTPIN (-6575 8800) $PN 2
J 0
(-6565 8780);
DISPLAY 0.617021 (-6565 8780);
PAINT MONO (-6565 8780);
FORCEPROP 1 LAST MATERIAL X6S
J 0
(-6525 8800);
DISPLAY 0.617021 (-6525 8800);
PAINT SKYBLUE (-6525 8800);
FORCEPROP 1 LAST PACK_TYPE C0805
J 0
(-6525 8700);
DISPLAY 0.617021 (-6525 8700);
PAINT SKYBLUE (-6525 8700);
FORCEPROP 1 LAST TOLERANCE 20%
J 0
(-6525 8850);
DISPLAY 0.617021 (-6525 8850);
PAINT SKYBLUE (-6525 8850);
FORCEPROP 1 LAST VALUE 22UF
J 0
(-6525 8950);
DISPLAY 0.617021 (-6525 8950);
PAINT SKYBLUE (-6525 8950);
FORCEPROP 1 LAST VOLTAGE 16V
J 0
(-6525 8900);
DISPLAY 0.617021 (-6525 8900);
PAINT SKYBLUE (-6525 8900);
FORCEPROP 2 LAST CDS_LIB pure_quanta
J 0
(-6575 8900);
DISPLAY INVISIBLE (-6575 8900);
FORCEPROP 1 LAST PATH I11
J 0
(-6525 9050);
DISPLAY 0.978723 (-6525 9050);
PAINT WHITE (-6525 9050);
DISPLAY INVISIBLE (-6525 9050);
FORCEPROP 1 LAST PART_NUMBER CH6223MEA01
J 0
(-6525 8750);
DISPLAY 0.617021 (-6525 8750);
PAINT BLUE (-6525 8750);
DISPLAY INVISIBLE (-6525 8750);
FORCEADD Q_CAP..1
(-6175 8900);
FORCEPROP 1 LAST LOCATION PC1846
J 0
(-6125 9000);
DISPLAY 0.617021 (-6125 9000);
PAINT AQUA (-6125 9000);
FORCEPROP 0 LAST $SEC 1
J 0
(-6125 9050);
DISPLAY 0.680851 (-6125 9050);
PAINT MONO (-6125 9050);
DISPLAY INVISIBLE (-6125 9050);
FORCEPROP 0 LAST CDS_SEC 1
J 0
(-6125 9050);
DISPLAY 1.021277 (-6125 9050);
DISPLAY INVISIBLE (-6125 9050);
FORCEPROP 1 LASTPIN (-6175 9000) $PN 1
J 0
(-6165 8980);
DISPLAY 0.787234 (-6165 8980);
PAINT MONO (-6165 8980);
FORCEPROP 1 LASTPIN (-6175 8800) $PN 2
J 0
(-6165 8780);
DISPLAY 0.787234 (-6165 8780);
PAINT MONO (-6165 8780);
FORCEPROP 1 LAST VALUE 1UF
J 0
(-6125 8950);
DISPLAY 0.617021 (-6125 8950);
PAINT SKYBLUE (-6125 8950);
FORCEPROP 1 LAST VOLTAGE 16V
J 0
(-6125 8900);
DISPLAY 0.617021 (-6125 8900);
PAINT SKYBLUE (-6125 8900);
FORCEPROP 1 LAST TOLERANCE 10%
J 0
(-6125 8850);
DISPLAY 0.617021 (-6125 8850);
PAINT SKYBLUE (-6125 8850);
FORCEPROP 1 LAST MATERIAL X6S
J 0
(-6125 8800);
DISPLAY 0.617021 (-6125 8800);
PAINT SKYBLUE (-6125 8800);
FORCEPROP 1 LAST PACK_TYPE C0402
J 0
(-6125 8700);
DISPLAY 0.617021 (-6125 8700);
PAINT SKYBLUE (-6125 8700);
FORCEPROP 2 LAST CDS_LIB pure_quanta
J 0
(-6175 8900);
DISPLAY INVISIBLE (-6175 8900);
FORCEPROP 1 LAST PATH I13
J 0
(-6125 9050);
DISPLAY 0.978723 (-6125 9050);
PAINT WHITE (-6125 9050);
DISPLAY INVISIBLE (-6125 9050);
FORCEPROP 1 LAST PART_NUMBER CH5103KEB01
J 0
(-6125 8750);
DISPLAY 0.489362 (-6125 8750);
PAINT BLUE (-6125 8750);
DISPLAY INVISIBLE (-6125 8750);
FORCEADD GND..1
(-5887 6443);
FORCEPROP 3 LASTPIN (-5887 6493) SIG_NAME GND\g
J 0
(-5877 6503);
DISPLAY 0.659574 (-5877 6503);
PAINT MONO (-5877 6503);
DISPLAY INVISIBLE (-5877 6503);
FORCEPROP 1 LAST SIZE 1B
J 0
(-5812 6393);
DISPLAY 0.872340 (-5812 6393);
PAINT AQUA (-5812 6393);
DISPLAY INVISIBLE (-5812 6393);
FORCEPROP 2 LAST CDS_LIB pure_quanta_power
J 0
(-5887 6443);
DISPLAY INVISIBLE (-5887 6443);
FORCEPROP 1 LAST HDL_POWER GND
J 0
(-5887 6593);
DISPLAY 0.872340 (-5887 6593);
PAINT GREEN (-5887 6593);
DISPLAY INVISIBLE (-5887 6593);
FORCEPROP 1 LAST PATH I14
J 0
(-5812 6443);
DISPLAY 0.872340 (-5812 6443);
PAINT AQUA (-5812 6443);
DISPLAY INVISIBLE (-5812 6443);
FORCEADD Q_RES..2
(-5887 6732);
FORCEPROP 1 LAST LOCATION PR8089
J 0
(-5842 6857);
DISPLAY 0.617021 (-5842 6857);
PAINT AQUA (-5842 6857);
FORCEPROP 2 LAST SEC 1
J 0
(-5825 6975);
DISPLAY 0.680851 (-5825 6975);
PAINT MONO (-5825 6975);
DISPLAY INVISIBLE (-5825 6975);
FORCEPROP 1 LASTPIN (-5887 6832) $PN 1
J 0
(-5882 6794);
DISPLAY 0.617021 (-5882 6794);
FORCEPROP 1 LASTPIN (-5887 6632) $PN 2
J 0
(-5882 6642);
DISPLAY 0.617021 (-5882 6642);
FORCEPROP 1 LAST MATERIAL CHIP
J 0
(-5847 6657);
DISPLAY 0.617021 (-5847 6657);
PAINT SKYBLUE (-5847 6657);
FORCEPROP 1 LAST PACK_TYPE 0402LF
J 0
(-5847 6557);
DISPLAY 0.617021 (-5847 6557);
PAINT SKYBLUE (-5847 6557);
FORCEPROP 1 LAST TOLERANCE 1%
J 0
(-5842 6757);
DISPLAY 0.617021 (-5842 6757);
PAINT SKYBLUE (-5842 6757);
FORCEPROP 1 LAST WATTAGE 1/16W
J 0
(-5847 6707);
DISPLAY 0.617021 (-5847 6707);
PAINT SKYBLUE (-5847 6707);
FORCEPROP 1 LAST VALUE 16.9K
J 0
(-5842 6807);
DISPLAY 0.617021 (-5842 6807);
PAINT SKYBLUE (-5842 6807);
FORCEPROP 2 LAST SEC_TYPE 0402LF
J 0
(-5825 6975);
DISPLAY 1.021277 (-5825 6975);
DISPLAY INVISIBLE (-5825 6975);
FORCEPROP 2 LAST CDS_LIB pure_quanta
R 3
J 0
(-5887 6732);
DISPLAY INVISIBLE (-5887 6732);
FORCEPROP 1 LAST PATH I15
J 0
(-5837 6907);
DISPLAY 0.978723 (-5837 6907);
PAINT WHITE (-5837 6907);
DISPLAY INVISIBLE (-5837 6907);
FORCEPROP 1 LAST PART_NUMBER CS31692FB03
J 0
(-5847 6607);
DISPLAY 0.617021 (-5847 6607);
PAINT BLUE (-5847 6607);
DISPLAY INVISIBLE (-5847 6607);
FORCEADD GND..1
(-4375 6625);
FORCEPROP 3 LASTPIN (-4375 6675) SIG_NAME GND\g
J 0
(-4365 6685);
DISPLAY 0.659574 (-4365 6685);
PAINT MONO (-4365 6685);
DISPLAY INVISIBLE (-4365 6685);
FORCEPROP 1 LAST SIZE 1B
J 0
(-4300 6575);
DISPLAY 0.872340 (-4300 6575);
PAINT AQUA (-4300 6575);
DISPLAY INVISIBLE (-4300 6575);
FORCEPROP 2 LAST CDS_LIB pure_quanta_power
J 0
(-4375 6625);
DISPLAY INVISIBLE (-4375 6625);
FORCEPROP 1 LAST HDL_POWER GND
J 0
(-4375 6775);
DISPLAY 0.872340 (-4375 6775);
PAINT GREEN (-4375 6775);
DISPLAY INVISIBLE (-4375 6775);
FORCEPROP 1 LAST PATH I16
J 0
(-4300 6625);
DISPLAY 0.872340 (-4300 6625);
PAINT AQUA (-4300 6625);
DISPLAY INVISIBLE (-4300 6625);
FORCEADD GND..1
(-4250 6625);
FORCEPROP 3 LASTPIN (-4250 6675) SIG_NAME GND\g
J 0
(-4240 6685);
DISPLAY 0.659574 (-4240 6685);
PAINT MONO (-4240 6685);
DISPLAY INVISIBLE (-4240 6685);
FORCEPROP 1 LAST SIZE 1B
J 0
(-4175 6575);
DISPLAY 0.872340 (-4175 6575);
PAINT AQUA (-4175 6575);
DISPLAY INVISIBLE (-4175 6575);
FORCEPROP 2 LAST CDS_LIB pure_quanta_power
J 0
(-4250 6625);
DISPLAY INVISIBLE (-4250 6625);
FORCEPROP 1 LAST HDL_POWER GND
J 0
(-4250 6775);
DISPLAY 0.872340 (-4250 6775);
PAINT GREEN (-4250 6775);
DISPLAY INVISIBLE (-4250 6775);
FORCEPROP 1 LAST PATH I17
J 0
(-4175 6625);
DISPLAY 0.872340 (-4175 6625);
PAINT AQUA (-4175 6625);
DISPLAY INVISIBLE (-4175 6625);
FORCEADD GND..1
(-5575 7375);
FORCEPROP 3 LASTPIN (-5575 7425) SIG_NAME GND\g
J 0
(-5565 7435);
DISPLAY 0.659574 (-5565 7435);
PAINT MONO (-5565 7435);
DISPLAY INVISIBLE (-5565 7435);
FORCEPROP 2 LAST CDS_LIB pure_quanta_power
J 0
(-5575 7375);
DISPLAY INVISIBLE (-5575 7375);
FORCEPROP 1 LAST SIZE 1B
J 0
(-5500 7325);
DISPLAY 0.872340 (-5500 7325);
PAINT AQUA (-5500 7325);
DISPLAY INVISIBLE (-5500 7325);
FORCEPROP 1 LAST HDL_POWER GND
J 0
(-5575 7525);
DISPLAY 0.872340 (-5575 7525);
PAINT GREEN (-5575 7525);
DISPLAY INVISIBLE (-5575 7525);
FORCEPROP 1 LAST PATH I18
J 0
(-5500 7375);
DISPLAY 0.872340 (-5500 7375);
PAINT AQUA (-5500 7375);
DISPLAY INVISIBLE (-5500 7375);
FORCEADD Q_CAP..1
(-4250 6850);
FORCEPROP 1 LAST LOCATION PC1853
J 0
(-4200 6975);
DISPLAY 0.617021 (-4200 6975);
PAINT AQUA (-4200 6975);
FORCEPROP 2 LAST $SEC 1
J 0
(-4200 7050);
DISPLAY 0.680851 (-4200 7050);
PAINT MONO (-4200 7050);
DISPLAY INVISIBLE (-4200 7050);
FORCEPROP 2 LAST CDS_SEC 1
J 0
(-4200 7050);
DISPLAY 0.680851 (-4200 7050);
DISPLAY INVISIBLE (-4200 7050);
FORCEPROP 1 LASTPIN (-4250 6950) $PN 1
J 0
(-4240 6930);
DISPLAY 0.617021 (-4240 6930);
FORCEPROP 1 LASTPIN (-4250 6750) $PN 2
J 0
(-4240 6730);
DISPLAY 0.617021 (-4240 6730);
FORCEPROP 1 LAST PACK_TYPE 0402
J 0
(-4200 6675);
DISPLAY 0.617021 (-4200 6675);
PAINT SKYBLUE (-4200 6675);
FORCEPROP 1 LAST MATERIAL X7R
J 0
(-4200 6775);
DISPLAY 0.617021 (-4200 6775);
PAINT SKYBLUE (-4200 6775);
FORCEPROP 1 LAST TOLERANCE 10%
J 0
(-4200 6825);
DISPLAY 0.617021 (-4200 6825);
PAINT SKYBLUE (-4200 6825);
FORCEPROP 1 LAST VOLTAGE 25V
J 0
(-4200 6875);
DISPLAY 0.617021 (-4200 6875);
PAINT SKYBLUE (-4200 6875);
FORCEPROP 1 LAST VALUE 0.1UF
J 0
(-4200 6925);
DISPLAY 0.617021 (-4200 6925);
PAINT SKYBLUE (-4200 6925);
FORCEPROP 2 LAST CDS_LIB pure_quanta
J 0
(-4250 6850);
DISPLAY INVISIBLE (-4250 6850);
FORCEPROP 1 LAST PATH I19
J 0
(-4200 7000);
DISPLAY 0.978723 (-4200 7000);
PAINT WHITE (-4200 7000);
DISPLAY INVISIBLE (-4200 7000);
FORCEPROP 1 LAST PART_NUMBER CH4104K1B00
J 0
(-4200 6725);
DISPLAY 0.617021 (-4200 6725);
PAINT BLUE (-4200 6725);
DISPLAY INVISIBLE (-4200 6725);
FORCEADD Q_CAP..1
(-8200 8925);
FORCEPROP 1 LAST LOCATION PC1648
J 0
(-8150 9025);
DISPLAY 0.787234 (-8150 9025);
FORCEPROP 0 LAST $SEC 1
J 0
(-8150 9075);
DISPLAY 0.680851 (-8150 9075);
PAINT MONO (-8150 9075);
DISPLAY INVISIBLE (-8150 9075);
FORCEPROP 0 LAST CDS_SEC 1
J 0
(-8150 9075);
DISPLAY 1.021277 (-8150 9075);
DISPLAY INVISIBLE (-8150 9075);
FORCEPROP 1 LASTPIN (-8200 9025) $PN 1
J 0
(-8190 9005);
DISPLAY 0.787234 (-8190 9005);
PAINT MONO (-8190 9005);
FORCEPROP 1 LASTPIN (-8200 8825) $PN 2
J 0
(-8190 8805);
DISPLAY 0.787234 (-8190 8805);
PAINT MONO (-8190 8805);
FORCEPROP 1 LAST MATERIAL X6S
J 0
(-8150 8825);
DISPLAY 0.787234 (-8150 8825);
FORCEPROP 1 LAST TOLERANCE 10%
J 0
(-8150 8875);
DISPLAY 0.787234 (-8150 8875);
FORCEPROP 1 LAST VOLTAGE 25V
J 0
(-8150 8925);
DISPLAY 0.787234 (-8150 8925);
FORCEPROP 1 LAST VALUE 0.1UF
J 0
(-8150 8975);
DISPLAY 0.787234 (-8150 8975);
FORCEPROP 1 LAST PACK_TYPE C0402
J 0
(-8150 8725);
DISPLAY 0.787234 (-8150 8725);
FORCEPROP 2 LAST CDS_LIB pure_quanta
J 0
(-8200 8925);
DISPLAY INVISIBLE (-8200 8925);
FORCEPROP 1 LAST PATH I2
J 0
(-8150 9075);
DISPLAY 0.978723 (-8150 9075);
PAINT WHITE (-8150 9075);
DISPLAY INVISIBLE (-8150 9075);
FORCEPROP 1 LAST PART_NUMBER CH4104KEB00
J 0
(-8150 8775);
DISPLAY 0.787234 (-8150 8775);
DISPLAY INVISIBLE (-8150 8775);
FORCEADD Q_CAP..2
(-2325 6625);
FORCEPROP 1 LAST LOCATION PC1877
J 1
(-2325 6725);
DISPLAY 0.617021 (-2325 6725);
PAINT AQUA (-2325 6725);
FORCEPROP 0 LAST $SEC 1
J 0
(-2325 6775);
DISPLAY 0.680851 (-2325 6775);
PAINT MONO (-2325 6775);
DISPLAY INVISIBLE (-2325 6775);
FORCEPROP 0 LAST CDS_SEC 1
J 0
(-2325 6775);
DISPLAY 0.680851 (-2325 6775);
DISPLAY INVISIBLE (-2325 6775);
FORCEPROP 1 LASTPIN (-2425 6625) $PN 1
J 0
(-2435 6640);
DISPLAY 0.617021 (-2435 6640);
PAINT MONO (-2435 6640);
FORCEPROP 1 LASTPIN (-2225 6625) $PN 2
J 0
(-2240 6640);
DISPLAY 0.617021 (-2240 6640);
PAINT MONO (-2240 6640);
FORCEPROP 1 LAST MATERIAL NPO
J 0
(-2325 6475);
DISPLAY 0.617021 (-2325 6475);
PAINT SKYBLUE (-2325 6475);
FORCEPROP 1 LAST TOLERANCE 5%
J 2
(-2325 6475);
DISPLAY 0.617021 (-2325 6475);
PAINT SKYBLUE (-2325 6475);
FORCEPROP 1 LAST PACK_TYPE 0402
J 1
(-2325 6425);
DISPLAY 0.617021 (-2325 6425);
PAINT SKYBLUE (-2325 6425);
FORCEPROP 1 LAST VOLTAGE 50V
J 0
(-2325 6525);
DISPLAY 0.617021 (-2325 6525);
PAINT SKYBLUE (-2325 6525);
FORCEPROP 1 LAST VALUE 47PF
J 2
(-2325 6525);
DISPLAY 0.617021 (-2325 6525);
PAINT SKYBLUE (-2325 6525);
FORCEPROP 2 LAST CDS_LIB pure_quanta
J 0
(-2325 6625);
DISPLAY INVISIBLE (-2325 6625);
FORCEPROP 1 LAST PATH I20
J 0
(-2325 6825);
DISPLAY 0.978723 (-2325 6825);
PAINT WHITE (-2325 6825);
DISPLAY INVISIBLE (-2325 6825);
FORCEPROP 1 LAST PART_NUMBER TMP_QCH04706JB01
J 1
(-2325 6675);
DISPLAY 0.617021 (-2325 6675);
PAINT BLUE (-2325 6675);
DISPLAY INVISIBLE (-2325 6675);
FORCEADD GND..1
(-3825 6700);
FORCEPROP 3 LASTPIN (-3825 6750) SIG_NAME GND\g
J 0
(-3815 6760);
DISPLAY 0.659574 (-3815 6760);
PAINT MONO (-3815 6760);
DISPLAY INVISIBLE (-3815 6760);
FORCEPROP 1 LAST SIZE 1B
J 0
(-3750 6650);
DISPLAY 0.872340 (-3750 6650);
PAINT AQUA (-3750 6650);
DISPLAY INVISIBLE (-3750 6650);
FORCEPROP 2 LAST CDS_LIB pure_quanta_power
J 0
(-3825 6700);
DISPLAY INVISIBLE (-3825 6700);
FORCEPROP 1 LAST HDL_POWER GND
J 0
(-3825 6850);
DISPLAY 0.872340 (-3825 6850);
PAINT GREEN (-3825 6850);
DISPLAY INVISIBLE (-3825 6850);
FORCEPROP 1 LAST PATH I21
J 0
(-3750 6700);
DISPLAY 0.872340 (-3750 6700);
PAINT AQUA (-3750 6700);
DISPLAY INVISIBLE (-3750 6700);
FORCEADD GND..1
(-3675 6700);
FORCEPROP 3 LASTPIN (-3675 6750) SIG_NAME GND\g
J 0
(-3665 6760);
DISPLAY 0.659574 (-3665 6760);
PAINT MONO (-3665 6760);
DISPLAY INVISIBLE (-3665 6760);
FORCEPROP 1 LAST SIZE 1B
J 0
(-3600 6650);
DISPLAY 0.872340 (-3600 6650);
PAINT AQUA (-3600 6650);
DISPLAY INVISIBLE (-3600 6650);
FORCEPROP 2 LAST CDS_LIB pure_quanta_power
J 0
(-3675 6700);
DISPLAY INVISIBLE (-3675 6700);
FORCEPROP 1 LAST HDL_POWER GND
J 0
(-3675 6850);
DISPLAY 0.872340 (-3675 6850);
PAINT GREEN (-3675 6850);
DISPLAY INVISIBLE (-3675 6850);
FORCEPROP 1 LAST PATH I22
J 0
(-3600 6700);
DISPLAY 0.872340 (-3600 6700);
PAINT AQUA (-3600 6700);
DISPLAY INVISIBLE (-3600 6700);
FORCEADD Q_RES..2
(-3675 7025);
FORCEPROP 1 LAST LOCATION PR8091
J 0
(-3630 7150);
DISPLAY 0.617021 (-3630 7150);
PAINT AQUA (-3630 7150);
FORCEPROP 2 LAST $SEC 1
J 0
(-3625 7250);
DISPLAY 0.680851 (-3625 7250);
PAINT MONO (-3625 7250);
DISPLAY INVISIBLE (-3625 7250);
FORCEPROP 2 LAST CDS_SEC 1
J 0
(-3625 7250);
DISPLAY 0.680851 (-3625 7250);
DISPLAY INVISIBLE (-3625 7250);
FORCEPROP 1 LASTPIN (-3675 7125) $PN 1
J 0
(-3670 7087);
DISPLAY 0.617021 (-3670 7087);
FORCEPROP 1 LASTPIN (-3675 6925) $PN 2
J 0
(-3670 6935);
DISPLAY 0.617021 (-3670 6935);
FORCEPROP 1 LAST PACK_TYPE 0402LF
J 0
(-3635 6850);
DISPLAY 0.617021 (-3635 6850);
PAINT SKYBLUE (-3635 6850);
FORCEPROP 1 LAST TOLERANCE 0.1%
J 0
(-3630 7050);
DISPLAY 0.617021 (-3630 7050);
PAINT SKYBLUE (-3630 7050);
FORCEPROP 1 LAST VALUE 11.8K
J 0
(-3630 7100);
DISPLAY 0.617021 (-3630 7100);
PAINT SKYBLUE (-3630 7100);
FORCEPROP 1 LAST MATERIAL CHIP
J 0
(-3635 6950);
DISPLAY 0.617021 (-3635 6950);
PAINT SKYBLUE (-3635 6950);
FORCEPROP 1 LAST WATTAGE 1/16W
J 0
(-3635 7000);
DISPLAY 0.617021 (-3635 7000);
PAINT SKYBLUE (-3635 7000);
FORCEPROP 2 LAST CDS_LIB pure_quanta
J 0
(-3675 7025);
DISPLAY INVISIBLE (-3675 7025);
FORCEPROP 1 LAST PATH I23
J 0
(-3625 7200);
DISPLAY 0.978723 (-3625 7200);
PAINT WHITE (-3625 7200);
DISPLAY INVISIBLE (-3625 7200);
FORCEPROP 1 LAST PART_NUMBER CS31182BB06
J 0
(-3635 6900);
DISPLAY 0.617021 (-3635 6900);
PAINT BLUE (-3635 6900);
DISPLAY INVISIBLE (-3635 6900);
FORCEADD Q_CAP..1
(-3725 7900);
FORCEPROP 1 LAST LOCATION PC1847
J 0
(-3675 8075);
DISPLAY 0.617021 (-3675 8075);
PAINT AQUA (-3675 8075);
FORCEPROP 0 LAST $SEC 1
J 0
(-3675 8125);
DISPLAY 0.680851 (-3675 8125);
PAINT MONO (-3675 8125);
DISPLAY INVISIBLE (-3675 8125);
FORCEPROP 0 LAST CDS_SEC 1
J 0
(-3675 8125);
DISPLAY 1.021277 (-3675 8125);
DISPLAY INVISIBLE (-3675 8125);
FORCEPROP 1 LASTPIN (-3725 8000) $PN 1
J 0
(-3715 7980);
DISPLAY 0.787234 (-3715 7980);
PAINT MONO (-3715 7980);
FORCEPROP 1 LASTPIN (-3725 7800) $PN 2
J 0
(-3715 7780);
DISPLAY 0.787234 (-3715 7780);
PAINT MONO (-3715 7780);
FORCEPROP 1 LAST VALUE 0.22UF
J 0
(-3675 8025);
DISPLAY 0.617021 (-3675 8025);
PAINT SKYBLUE (-3675 8025);
FORCEPROP 1 LAST TOLERANCE 10%
J 0
(-3675 7925);
DISPLAY 0.617021 (-3675 7925);
PAINT SKYBLUE (-3675 7925);
FORCEPROP 1 LAST MATERIAL X7R
J 0
(-3675 7875);
DISPLAY 0.617021 (-3675 7875);
PAINT SKYBLUE (-3675 7875);
FORCEPROP 1 LAST PACK_TYPE C0402
J 0
(-3675 7775);
DISPLAY 0.617021 (-3675 7775);
PAINT SKYBLUE (-3675 7775);
FORCEPROP 1 LAST VOLTAGE 25V
J 0
(-3675 7975);
DISPLAY 0.617021 (-3675 7975);
PAINT SKYBLUE (-3675 7975);
FORCEPROP 2 LAST CDS_LIB pure_quanta
J 0
(-3725 7900);
DISPLAY INVISIBLE (-3725 7900);
FORCEPROP 1 LAST PATH I24
J 0
(-3675 8050);
DISPLAY 0.978723 (-3675 8050);
PAINT WHITE (-3675 8050);
DISPLAY INVISIBLE (-3675 8050);
FORCEPROP 1 LAST PART_NUMBER CH4224K1B01
J 0
(-3675 7825);
DISPLAY 0.617021 (-3675 7825);
PAINT BLUE (-3675 7825);
DISPLAY INVISIBLE (-3675 7825);
FORCEADD Q_RES..2
(-3725 8625);
FORCEPROP 1 LAST LOCATION R2356
J 0
(-3680 8750);
DISPLAY 0.617021 (-3680 8750);
PAINT AQUA (-3680 8750);
FORCEPROP 2 LAST SEC 1
J 0
(-3674 8854);
DISPLAY 0.680851 (-3674 8854);
PAINT MONO (-3674 8854);
DISPLAY INVISIBLE (-3674 8854);
FORCEPROP 1 LASTPIN (-3725 8725) $PN 1
J 0
(-3720 8687);
DISPLAY 0.617021 (-3720 8687);
FORCEPROP 1 LASTPIN (-3725 8525) $PN 2
J 0
(-3720 8535);
DISPLAY 0.617021 (-3720 8535);
FORCEPROP 1 LAST PACK_TYPE 0402LF
J 0
(-3685 8450);
DISPLAY 0.617021 (-3685 8450);
PAINT SKYBLUE (-3685 8450);
FORCEPROP 1 LAST TOLERANCE 1%
J 0
(-3680 8650);
DISPLAY 0.617021 (-3680 8650);
PAINT SKYBLUE (-3680 8650);
FORCEPROP 1 LAST MATERIAL CHIP
J 0
(-3685 8550);
DISPLAY 0.617021 (-3685 8550);
PAINT SKYBLUE (-3685 8550);
FORCEPROP 1 LAST WATTAGE 1/16W
J 0
(-3685 8600);
DISPLAY 0.617021 (-3685 8600);
PAINT SKYBLUE (-3685 8600);
FORCEPROP 1 LAST VALUE 10K
J 0
(-3680 8700);
DISPLAY 0.617021 (-3680 8700);
PAINT SKYBLUE (-3680 8700);
FORCEPROP 2 LAST CDS_LIB pure_quanta
R 3
J 0
(-3725 8625);
PAINT MONO (-3725 8625);
DISPLAY INVISIBLE (-3725 8625);
FORCEPROP 2 LAST SEC_TYPE 0402LF
J 0
(-3674 8854);
DISPLAY 1.021277 (-3674 8854);
DISPLAY INVISIBLE (-3674 8854);
FORCEPROP 1 LAST PATH I25
J 0
(-3675 8800);
DISPLAY 0.978723 (-3675 8800);
PAINT WHITE (-3675 8800);
DISPLAY INVISIBLE (-3675 8800);
FORCEPROP 1 LAST PART_NUMBER CS31002FB08
J 0
(-3685 8500);
DISPLAY 0.617021 (-3685 8500);
PAINT BLUE (-3685 8500);
DISPLAY INVISIBLE (-3685 8500);
FORCEADD Q_RES..1
(-3150 8250);
FORCEPROP 1 LAST LOCATION R2316
J 0
(-3375 8250);
DISPLAY 0.638298 (-3375 8250);
FORCEPROP 0 LAST $SEC 1
J 0
(-3275 8450);
DISPLAY 0.680851 (-3275 8450);
PAINT MONO (-3275 8450);
DISPLAY INVISIBLE (-3275 8450);
FORCEPROP 0 LAST CDS_SEC 1
J 0
(-3275 8450);
DISPLAY 1.021277 (-3275 8450);
DISPLAY INVISIBLE (-3275 8450);
FORCEPROP 1 LASTPIN (-3250 8250) $PN 1
J 0
(-3238 8262);
DISPLAY 0.787234 (-3238 8262);
PAINT MONO (-3238 8262);
FORCEPROP 1 LASTPIN (-3050 8250) $PN 2
J 0
(-3088 8262);
DISPLAY 0.787234 (-3088 8262);
PAINT MONO (-3088 8262);
FORCEPROP 1 LAST WATTAGE 1/16W
J 2
(-2975 8350);
DISPLAY 0.617021 (-2975 8350);
PAINT SKYBLUE (-2975 8350);
FORCEPROP 1 LAST VALUE 0
J 2
(-3000 8250);
DISPLAY 0.617021 (-3000 8250);
PAINT SKYBLUE (-3000 8250);
FORCEPROP 1 LAST MATERIAL CHIP
J 0
(-3275 8350);
DISPLAY 0.617021 (-3275 8350);
PAINT SKYBLUE (-3275 8350);
FORCEPROP 1 LAST PACK_TYPE 0402LF
J 0
(-3275 8400);
DISPLAY 0.617021 (-3275 8400);
PAINT SKYBLUE (-3275 8400);
FORCEPROP 1 LAST TOLERANCE 5%
J 0
(-2975 8250);
DISPLAY 0.617021 (-2975 8250);
PAINT SKYBLUE (-2975 8250);
FORCEPROP 2 LAST CDS_LIB pure_quanta
J 0
(-3150 8250);
DISPLAY INVISIBLE (-3150 8250);
FORCEPROP 1 LAST PATH I26
J 0
(-3200 8400);
DISPLAY 0.978723 (-3200 8400);
PAINT WHITE (-3200 8400);
DISPLAY INVISIBLE (-3200 8400);
FORCEPROP 1 LAST PART_NUMBER CS00002JB13
J 0
(-3275 8300);
DISPLAY 0.617021 (-3275 8300);
PAINT BLUE (-3275 8300);
DISPLAY INVISIBLE (-3275 8300);
FORCEADD Q_RES..1
(-2300 6950);
FORCEPROP 1 LAST LOCATION PR8092
J 0
(-2678 6979);
DISPLAY 0.617021 (-2678 6979);
PAINT AQUA (-2678 6979);
FORCEPROP 2 LAST $SEC 1
J 0
(-2327 7163);
DISPLAY 0.680851 (-2327 7163);
PAINT MONO (-2327 7163);
DISPLAY INVISIBLE (-2327 7163);
FORCEPROP 2 LAST CDS_SEC 1
J 0
(-2327 7163);
DISPLAY 0.680851 (-2327 7163);
DISPLAY INVISIBLE (-2327 7163);
FORCEPROP 1 LASTPIN (-2400 6950) $PN 1
J 0
(-2388 6962);
DISPLAY 0.617021 (-2388 6962);
FORCEPROP 1 LASTPIN (-2200 6950) $PN 2
J 0
(-2238 6962);
DISPLAY 0.617021 (-2238 6962);
FORCEPROP 1 LAST TOLERANCE 1%
J 0
(-2200 6850);
DISPLAY 0.638298 (-2200 6850);
PAINT SKYBLUE (-2200 6850);
FORCEPROP 1 LAST MATERIAL CHIP
J 0
(-2600 6850);
DISPLAY 0.617021 (-2600 6850);
PAINT SKYBLUE (-2600 6850);
FORCEPROP 1 LAST VALUE 86.6K
J 2
(-1975 7000);
DISPLAY 0.617021 (-1975 7000);
PAINT SKYBLUE (-1975 7000);
FORCEPROP 1 LAST PACK_TYPE 0402LF
J 0
(-2613 6886);
DISPLAY 0.617021 (-2613 6886);
PAINT SKYBLUE (-2613 6886);
FORCEPROP 1 LAST WATTAGE 1/16W
J 2
(-1726 6968);
DISPLAY 0.978723 (-1726 6968);
PAINT SKYBLUE (-1726 6968);
DISPLAY INVISIBLE (-1726 6968);
FORCEPROP 2 LAST CDS_LIB pure_quanta
J 0
(-2300 6950);
DISPLAY INVISIBLE (-2300 6950);
FORCEPROP 1 LAST PATH I27
J 0
(-2350 7100);
DISPLAY 0.978723 (-2350 7100);
PAINT WHITE (-2350 7100);
DISPLAY INVISIBLE (-2350 7100);
FORCEPROP 1 LAST PART_NUMBER CS38662FB05
J 0
(-2200 6900);
DISPLAY 0.617021 (-2200 6900);
PAINT BLUE (-2200 6900);
DISPLAY INVISIBLE (-2200 6900);
FORCEADD Q_INDUCTOR..1
(-2825 7775);
FORCEPROP 1 LAST LOCATION PL8065
J 0
(-2950 7935);
DISPLAY 0.617021 (-2950 7935);
PAINT AQUA (-2950 7935);
FORCEPROP 2 LAST $SEC 1
J 0
(-2950 8075);
DISPLAY 0.680851 (-2950 8075);
PAINT MONO (-2950 8075);
DISPLAY INVISIBLE (-2950 8075);
FORCEPROP 2 LAST CDS_SEC 1
J 0
(-2950 8075);
DISPLAY 0.680851 (-2950 8075);
DISPLAY INVISIBLE (-2950 8075);
FORCEPROP 2 LASTPIN (-2925 7750) $PN 1
J 2
(-2935 7760);
DISPLAY 0.617021 (-2935 7760);
FORCEPROP 2 LASTPIN (-2725 7750) $PN 2
J 0
(-2715 7760);
DISPLAY 0.617021 (-2715 7760);
FORCEPROP 2 LAST PACK_TYPE SMLF
J 0
(-2950 8025);
DISPLAY 0.617021 (-2950 8025);
PAINT SKYBLUE (-2950 8025);
FORCEPROP 1 LAST MATERIAL IND
J 0
(-2950 7830);
DISPLAY 0.617021 (-2950 7830);
PAINT SKYBLUE (-2950 7830);
FORCEPROP 2 LAST VALUE 4.7UH
J 0
(-2950 7975);
DISPLAY 0.617021 (-2950 7975);
PAINT SKYBLUE (-2950 7975);
FORCEPROP 2 LAST CDS_LIB pure_quanta
J 0
(-2825 7775);
DISPLAY INVISIBLE (-2825 7775);
FORCEPROP 1 LAST NEEDS_NO_SIZE TRUE
J 0
(-2825 7775);
DISPLAY 0.468085 (-2825 7775);
PAINT GREEN (-2825 7775);
DISPLAY INVISIBLE (-2825 7775);
FORCEPROP 1 LAST PATH I28
J 0
(-2750 7830);
DISPLAY 0.723404 (-2750 7830);
PAINT GREEN (-2750 7830);
DISPLAY INVISIBLE (-2750 7830);
FORCEPROP 1 LAST PART_NUMBER CV-47A0MZ10
J 0
(-2950 7885);
DISPLAY 0.617021 (-2950 7885);
PAINT BLUE (-2950 7885);
DISPLAY INVISIBLE (-2950 7885);
FORCEADD OFFPAGE..2
(-2075 8250);
FORCEPROP 2 LAST $XR1 190 
J 0
(-1796 8250);
DISPLAY 0.638298 (-1796 8250);
PAINT MONO (-1796 8250);
FORCEPROP 2 LAST $XR0 85 
J 0
(-1886 8250);
DISPLAY 0.638298 (-1886 8250);
PAINT MONO (-1886 8250);
FORCEPROP 2 LAST BOM_COST VR_SYSTEM 
J 0
(-1725 8300);
DISPLAY 0.680851 (-1725 8300);
DISPLAY INVISIBLE (-1725 8300);
FORCEPROP 2 LAST CDS_LIB standard
J 0
(-2075 8250);
PAINT MONO (-2075 8250);
DISPLAY INVISIBLE (-2075 8250);
FORCEPROP 1 LAST OFFPAGE TRUE
J 0
(-1750 8125);
DISPLAY 0.531915 (-1750 8125);
PAINT GREEN (-1750 8125);
DISPLAY INVISIBLE (-1750 8125);
FORCEPROP 1 LAST COMMENT_BODY TRUE
J 0
(-2120 8155);
DISPLAY 0.531915 (-2120 8155);
PAINT GREEN (-2120 8155);
DISPLAY INVISIBLE (-2120 8155);
FORCEPROP 2 LAST PATH I29
J 0
(-1875 8300);
DISPLAY 0.680851 (-1875 8300);
DISPLAY INVISIBLE (-1875 8300);
FORCEADD P1V0_AUX..1
(-8196 9345);
FORCEPROP 3 LASTPIN (-8196 9295) SIG_NAME P12V_AUX\g
J 0
(-8186 9305);
DISPLAY 0.659574 (-8186 9305);
PAINT MONO (-8186 9305);
DISPLAY INVISIBLE (-8186 9305);
FORCEPROP 1 LAST HDL_POWER P12V_AUX
J 1
(-8185 9392);
DISPLAY 0.617021 (-8185 9392);
PAINT GREEN (-8185 9392);
FORCEPROP 2 LAST CDS_LIB pure_quanta_power
J 0
(-8196 9345);
DISPLAY INVISIBLE (-8196 9345);
FORCEPROP 1 LAST PATH I3
J 0
(-8146 9370);
DISPLAY 0.872340 (-8146 9370);
PAINT AQUA (-8146 9370);
DISPLAY INVISIBLE (-8146 9370);
FORCEADD Q_CAPP..1
(-1550 7500);
FORCEPROP 1 LAST LOCATION PC1845
J 0
(-1500 7600);
DISPLAY 0.617021 (-1500 7600);
PAINT AQUA (-1500 7600);
FORCEPROP 0 LAST $SEC 1
J 0
(-1500 7650);
DISPLAY 0.680851 (-1500 7650);
PAINT MONO (-1500 7650);
DISPLAY INVISIBLE (-1500 7650);
FORCEPROP 0 LAST CDS_SEC 1
J 0
(-1500 7650);
DISPLAY 0.680851 (-1500 7650);
DISPLAY INVISIBLE (-1500 7650);
FORCEPROP 1 LASTPIN (-1550 7600) $PN 1
J 0
(-1540 7585);
DISPLAY 0.617021 (-1540 7585);
PAINT MONO (-1540 7585);
FORCEPROP 1 LASTPIN (-1550 7400) $PN 2
J 0
(-1540 7385);
DISPLAY 0.617021 (-1540 7385);
PAINT MONO (-1540 7385);
FORCEPROP 1 LAST VALUE 220UF
J 0
(-1500 7550);
DISPLAY 0.617021 (-1500 7550);
PAINT SKYBLUE (-1500 7550);
FORCEPROP 1 LAST PACK_TYPE SMLF
J 0
(-1500 7350);
DISPLAY 0.617021 (-1500 7350);
PAINT SKYBLUE (-1500 7350);
FORCEPROP 1 LAST VOLTAGE 6.3V
J 0
(-1500 7450);
DISPLAY 0.617021 (-1500 7450);
PAINT SKYBLUE (-1500 7450);
FORCEPROP 1 LAST TOLERANCE 20%
J 0
(-1500 7500);
DISPLAY 0.617021 (-1500 7500);
PAINT SKYBLUE (-1500 7500);
FORCEPROP 1 LAST MATERIAL ALUM
J 0
(-1500 7400);
DISPLAY 0.617021 (-1500 7400);
PAINT SKYBLUE (-1500 7400);
FORCEPROP 2 LAST CDS_LIB pure_quanta
J 0
(-1550 7500);
DISPLAY INVISIBLE (-1550 7500);
FORCEPROP 1 LAST PATH I30
J 0
(-1500 7650);
DISPLAY 0.978723 (-1500 7650);
DISPLAY INVISIBLE (-1500 7650);
FORCEPROP 1 LAST PART_NUMBER CC72201MZ28
J 0
(-1500 7300);
DISPLAY 0.617021 (-1500 7300);
PAINT BLUE (-1500 7300);
DISPLAY INVISIBLE (-1500 7300);
FORCEADD Q_CAP..1
(-1100 7500);
FORCEPROP 1 LAST LOCATION PC1855
J 0
(-1050 7600);
DISPLAY 0.617021 (-1050 7600);
PAINT AQUA (-1050 7600);
FORCEPROP 0 LAST $SEC 1
J 0
(-1050 7650);
DISPLAY 0.680851 (-1050 7650);
PAINT MONO (-1050 7650);
DISPLAY INVISIBLE (-1050 7650);
FORCEPROP 0 LAST CDS_SEC 1
J 0
(-1050 7650);
DISPLAY 0.680851 (-1050 7650);
DISPLAY INVISIBLE (-1050 7650);
FORCEPROP 1 LASTPIN (-1100 7600) $PN 1
J 0
(-1090 7580);
DISPLAY 0.617021 (-1090 7580);
PAINT MONO (-1090 7580);
FORCEPROP 1 LASTPIN (-1100 7400) $PN 2
J 0
(-1090 7380);
DISPLAY 0.617021 (-1090 7380);
PAINT MONO (-1090 7380);
FORCEPROP 1 LAST MATERIAL X6S
J 0
(-1050 7400);
DISPLAY 0.617021 (-1050 7400);
PAINT SKYBLUE (-1050 7400);
FORCEPROP 1 LAST VOLTAGE 10V
J 0
(-1050 7500);
DISPLAY 0.617021 (-1050 7500);
PAINT SKYBLUE (-1050 7500);
FORCEPROP 1 LAST TOLERANCE 20%
J 0
(-1050 7450);
DISPLAY 0.617021 (-1050 7450);
PAINT SKYBLUE (-1050 7450);
FORCEPROP 1 LAST PACK_TYPE C0805
J 0
(-1050 7300);
DISPLAY 0.617021 (-1050 7300);
PAINT SKYBLUE (-1050 7300);
FORCEPROP 1 LAST VALUE 22UF
J 0
(-1050 7550);
DISPLAY 0.617021 (-1050 7550);
PAINT SKYBLUE (-1050 7550);
FORCEPROP 2 LAST CDS_LIB pure_quanta
J 0
(-1100 7500);
DISPLAY INVISIBLE (-1100 7500);
FORCEPROP 1 LAST PATH I31
J 0
(-1050 7650);
DISPLAY 0.978723 (-1050 7650);
PAINT WHITE (-1050 7650);
DISPLAY INVISIBLE (-1050 7650);
FORCEPROP 1 LAST PART_NUMBER CH6222MEA01
J 0
(-1050 7350);
DISPLAY 0.617021 (-1050 7350);
PAINT BLUE (-1050 7350);
DISPLAY INVISIBLE (-1050 7350);
FORCEADD Q_CAP..1
(-600 7500);
FORCEPROP 1 LAST LOCATION PC1856
J 0
(-550 7600);
DISPLAY 0.617021 (-550 7600);
PAINT AQUA (-550 7600);
FORCEPROP 0 LAST $SEC 1
J 0
(-550 7650);
DISPLAY 0.680851 (-550 7650);
PAINT MONO (-550 7650);
DISPLAY INVISIBLE (-550 7650);
FORCEPROP 0 LAST CDS_SEC 1
J 0
(-550 7650);
DISPLAY 0.680851 (-550 7650);
DISPLAY INVISIBLE (-550 7650);
FORCEPROP 1 LASTPIN (-600 7600) $PN 1
J 0
(-590 7580);
DISPLAY 0.617021 (-590 7580);
PAINT MONO (-590 7580);
FORCEPROP 1 LASTPIN (-600 7400) $PN 2
J 0
(-590 7380);
DISPLAY 0.617021 (-590 7380);
PAINT MONO (-590 7380);
FORCEPROP 1 LAST TOLERANCE 20%
J 0
(-550 7450);
DISPLAY 0.617021 (-550 7450);
PAINT SKYBLUE (-550 7450);
FORCEPROP 1 LAST VOLTAGE 10V
J 0
(-550 7500);
DISPLAY 0.617021 (-550 7500);
PAINT SKYBLUE (-550 7500);
FORCEPROP 1 LAST VALUE 22UF
J 0
(-550 7550);
DISPLAY 0.617021 (-550 7550);
PAINT SKYBLUE (-550 7550);
FORCEPROP 1 LAST PACK_TYPE C0805
J 0
(-550 7300);
DISPLAY 0.617021 (-550 7300);
PAINT SKYBLUE (-550 7300);
FORCEPROP 1 LAST MATERIAL X6S
J 0
(-550 7400);
DISPLAY 0.617021 (-550 7400);
PAINT SKYBLUE (-550 7400);
FORCEPROP 2 LAST CDS_LIB pure_quanta
J 0
(-600 7500);
DISPLAY INVISIBLE (-600 7500);
FORCEPROP 1 LAST PATH I32
J 0
(-550 7650);
DISPLAY 0.978723 (-550 7650);
PAINT WHITE (-550 7650);
DISPLAY INVISIBLE (-550 7650);
FORCEPROP 1 LAST PART_NUMBER CH6222MEA01
J 0
(-550 7350);
DISPLAY 0.617021 (-550 7350);
PAINT BLUE (-550 7350);
DISPLAY INVISIBLE (-550 7350);
FORCEADD GND..1
(-175 7100);
FORCEPROP 3 LASTPIN (-175 7150) SIG_NAME GND\g
J 0
(-165 7160);
DISPLAY 0.659574 (-165 7160);
PAINT MONO (-165 7160);
DISPLAY INVISIBLE (-165 7160);
FORCEPROP 1 LAST SIZE 1B
J 0
(-100 7050);
DISPLAY 0.872340 (-100 7050);
PAINT AQUA (-100 7050);
DISPLAY INVISIBLE (-100 7050);
FORCEPROP 2 LAST CDS_LIB pure_quanta_power
J 0
(-175 7100);
DISPLAY INVISIBLE (-175 7100);
FORCEPROP 1 LAST HDL_POWER GND
J 0
(-175 7250);
DISPLAY 0.872340 (-175 7250);
PAINT GREEN (-175 7250);
DISPLAY INVISIBLE (-175 7250);
FORCEPROP 1 LAST PATH I33
J 0
(-100 7100);
DISPLAY 0.872340 (-100 7100);
PAINT AQUA (-100 7100);
DISPLAY INVISIBLE (-100 7100);
FORCEADD Q_CAP..1
(-175 7500);
FORCEPROP 1 LAST LOCATION PC1852
J 0
(-125 7600);
DISPLAY 0.617021 (-125 7600);
PAINT AQUA (-125 7600);
FORCEPROP 2 LAST SEC 1
J 0
(-123 7707);
DISPLAY 0.680851 (-123 7707);
PAINT MONO (-123 7707);
DISPLAY INVISIBLE (-123 7707);
FORCEPROP 1 LASTPIN (-175 7600) $PN 1
J 0
(-165 7580);
DISPLAY 0.617021 (-165 7580);
FORCEPROP 1 LASTPIN (-175 7400) $PN 2
J 0
(-165 7380);
DISPLAY 0.617021 (-165 7380);
FORCEPROP 1 LAST VOLTAGE 25V
J 0
(-125 7500);
DISPLAY 0.617021 (-125 7500);
PAINT SKYBLUE (-125 7500);
FORCEPROP 1 LAST VALUE 0.1UF
J 0
(-125 7550);
DISPLAY 0.617021 (-125 7550);
PAINT SKYBLUE (-125 7550);
FORCEPROP 1 LAST TOLERANCE 10%
J 0
(-125 7450);
DISPLAY 0.617021 (-125 7450);
PAINT SKYBLUE (-125 7450);
FORCEPROP 1 LAST MATERIAL X7R
J 0
(-125 7400);
DISPLAY 0.617021 (-125 7400);
PAINT SKYBLUE (-125 7400);
FORCEPROP 1 LAST PACK_TYPE 0402
J 0
(-125 7300);
DISPLAY 0.617021 (-125 7300);
PAINT SKYBLUE (-125 7300);
FORCEPROP 2 LAST SEC_TYPE 0402
J 0
(-125 7696);
DISPLAY 1.021277 (-125 7696);
DISPLAY INVISIBLE (-125 7696);
FORCEPROP 2 LAST CDS_LIB pure_quanta
J 0
(-175 7500);
PAINT MONO (-175 7500);
DISPLAY INVISIBLE (-175 7500);
FORCEPROP 1 LAST PATH I34
J 0
(-125 7650);
DISPLAY 0.978723 (-125 7650);
PAINT WHITE (-125 7650);
DISPLAY INVISIBLE (-125 7650);
FORCEPROP 1 LAST PART_NUMBER CH4104K1B00
J 0
(-125 7350);
DISPLAY 0.617021 (-125 7350);
PAINT BLUE (-125 7350);
DISPLAY INVISIBLE (-125 7350);
FORCEADD UNIVERSAL_POWER..1
(-3725 8925);
FORCEPROP 1 LAST HDL_POWER P5V_AUX_VCC
J 1
(-3725 8975);
DISPLAY 0.617021 (-3725 8975);
PAINT GREEN (-3725 8975);
FORCEPROP 2 LAST CDS_LIB pure_quanta_power
J 0
(-3725 8925);
DISPLAY INVISIBLE (-3725 8925);
FORCEPROP 1 LAST PATH I35
J 0
(-3675 8950);
DISPLAY 0.872340 (-3675 8950);
PAINT AQUA (-3675 8950);
DISPLAY INVISIBLE (-3675 8950);
FORCEADD P1V0..1
(325 8225);
FORCEPROP 3 LASTPIN (325 8175) SIG_NAME P5V_AUX\g
J 0
(335 8185);
DISPLAY 0.659574 (335 8185);
PAINT MONO (335 8185);
DISPLAY INVISIBLE (335 8185);
FORCEPROP 1 LAST HDL_POWER P5V_AUX
J 1
(325 8275);
DISPLAY 0.617021 (325 8275);
PAINT GREEN (325 8275);
FORCEPROP 2 LAST CDS_LIB pure_quanta_power
J 0
(325 8225);
PAINT MONO (325 8225);
DISPLAY INVISIBLE (325 8225);
FORCEPROP 1 LAST PATH I36
J 0
(375 8250);
DISPLAY 0.872340 (375 8250);
PAINT AQUA (375 8250);
DISPLAY INVISIBLE (375 8250);
FORCEADD Q_RES..1
(-5975 7450);
FORCEPROP 1 LAST LOCATION PR3337
J 0
(-6200 7475);
DISPLAY 0.638298 (-6200 7475);
FORCEPROP 0 LAST $SEC 1
J 0
(-5850 7525);
DISPLAY 0.680851 (-5850 7525);
PAINT MONO (-5850 7525);
DISPLAY INVISIBLE (-5850 7525);
FORCEPROP 0 LAST CDS_SEC 1
J 0
(-5850 7525);
DISPLAY 1.021277 (-5850 7525);
DISPLAY INVISIBLE (-5850 7525);
FORCEPROP 1 LASTPIN (-6075 7450) $PN 1
J 0
(-6063 7462);
DISPLAY 0.787234 (-6063 7462);
PAINT MONO (-6063 7462);
FORCEPROP 1 LASTPIN (-5875 7450) $PN 2
J 0
(-5913 7462);
DISPLAY 0.787234 (-5913 7462);
PAINT MONO (-5913 7462);
FORCEPROP 1 LAST VALUE 0
J 2
(-5950 7475);
DISPLAY 0.638298 (-5950 7475);
FORCEPROP 1 LAST WATTAGE 1/16W
J 2
(-5800 7400);
DISPLAY 0.638298 (-5800 7400);
FORCEPROP 1 LAST PACK_TYPE 0402LF
J 0
(-6175 7350);
DISPLAY 0.638298 (-6175 7350);
FORCEPROP 1 LAST TOLERANCE 5%
J 0
(-5850 7475);
DISPLAY 0.638298 (-5850 7475);
FORCEPROP 1 LAST MATERIAL CHIP
J 0
(-6175 7400);
DISPLAY 0.638298 (-6175 7400);
FORCEPROP 2 LAST CDS_LIB pure_quanta
J 0
(-5975 7450);
DISPLAY INVISIBLE (-5975 7450);
FORCEPROP 1 LAST PATH I37
J 0
(-6025 7600);
DISPLAY 0.978723 (-6025 7600);
PAINT WHITE (-6025 7600);
DISPLAY INVISIBLE (-6025 7600);
FORCEPROP 1 LAST PART_NUMBER CS00002JB13
J 0
(-5950 7350);
DISPLAY 0.638298 (-5950 7350);
DISPLAY INVISIBLE (-5950 7350);
FORCEADD MPQ8633AGLEC807Z..1
(-5000 7575);
FORCEPROP 1 LAST LOCATION U326
J 0
(-5250 8400);
DISPLAY 0.723404 (-5250 8400);
PAINT GREEN (-5250 8400);
FORCEPROP 0 LAST $SEC 1
J 0
(-5250 8650);
DISPLAY 0.680851 (-5250 8650);
PAINT MONO (-5250 8650);
DISPLAY INVISIBLE (-5250 8650);
FORCEPROP 0 LAST CDS_SEC 1
J 0
(-5225 8625);
DISPLAY 0.680851 (-5225 8625);
DISPLAY INVISIBLE (-5225 8625);
FORCEPROP 0 LASTPIN (-4600 6900) $PN 2
J 0
(-4590 6910);
DISPLAY 0.680851 (-4590 6910);
PAINT MONO (-4590 6910);
FORCEPROP 0 LASTPIN (-4600 8050) $PN 1
J 0
(-4590 8060);
DISPLAY 0.680851 (-4590 8060);
PAINT MONO (-4590 8060);
FORCEPROP 0 LASTPIN (-5400 6950) $PN 3
J 2
(-5410 6960);
DISPLAY 0.680851 (-5410 6960);
PAINT MONO (-5410 6960);
FORCEPROP 0 LASTPIN (-5400 7750) $PN 8
J 2
(-5410 7760);
DISPLAY 0.680851 (-5410 7760);
PAINT MONO (-5410 7760);
FORCEPROP 0 LASTPIN (-4600 7300) $PN 7
J 0
(-4590 7310);
DISPLAY 0.680851 (-4590 7310);
PAINT MONO (-4590 7310);
FORCEPROP 0 LASTPIN (-5400 7550) $PN 4
J 2
(-5410 7560);
DISPLAY 0.680851 (-5410 7560);
PAINT MONO (-5410 7560);
FORCEPROP 0 LASTPIN (-4600 6950) $PN 11_18
J 0
(-4590 6960);
DISPLAY 0.680851 (-4590 6960);
PAINT MONO (-4590 6960);
FORCEPROP 0 LASTPIN (-4600 8250) $PN 9
J 0
(-4590 8260);
DISPLAY 0.680851 (-4590 8260);
PAINT MONO (-4590 8260);
FORCEPROP 0 LASTPIN (-4600 7150) $PN 6
J 0
(-4590 7160);
DISPLAY 0.680851 (-4590 7160);
PAINT MONO (-4590 7160);
FORCEPROP 0 LASTPIN (-4600 7750) $PN 20
J 0
(-4590 7760);
DISPLAY 0.680851 (-4590 7760);
PAINT MONO (-4590 7760);
FORCEPROP 0 LASTPIN (-4600 7050) $PN 5
J 0
(-4590 7060);
DISPLAY 0.680851 (-4590 7060);
PAINT MONO (-4590 7060);
FORCEPROP 0 LASTPIN (-5400 7300) $PN 19
J 2
(-5410 7310);
DISPLAY 0.680851 (-5410 7310);
PAINT MONO (-5410 7310);
FORCEPROP 0 LASTPIN (-5400 8250) $PN 10
J 2
(-5410 8260);
DISPLAY 0.680851 (-5410 8260);
PAINT MONO (-5410 8260);
FORCEPROP 0 LASTPIN (-5400 8200) $PN 21
J 2
(-5410 8210);
DISPLAY 0.680851 (-5410 8210);
PAINT MONO (-5410 8210);
FORCEPROP 2 LAST PART_TYPE SMLF
J 0
(-5250 8600);
DISPLAY 0.680851 (-5250 8600);
FORCEPROP 1 LAST MATERIAL IC
J 0
(-5247 8340);
DISPLAY 0.723404 (-5247 8340);
PAINT GREEN (-5247 8340);
FORCEPROP 2 LAST VALUE MPQ8633AGLE-C807-Z
J 0
(-5250 8550);
DISPLAY 0.617021 (-5250 8550);
PAINT SKYBLUE (-5250 8550);
FORCEPROP 1 LAST NEEDS_NO_SIZE TRUE
J 0
(-5000 7575);
DISPLAY 0.723404 (-5000 7575);
PAINT GREEN (-5000 7575);
DISPLAY INVISIBLE (-5000 7575);
FORCEPROP 1 LAST CDS_LMAN_SYM_OUTLINE -250,725,250,-725
J 0
(-5000 7575);
DISPLAY 0.468085 (-5000 7575);
PAINT GREEN (-5000 7575);
DISPLAY INVISIBLE (-5000 7575);
FORCEPROP 2 LAST CDS_LIB pure_quanta
J 0
(-5000 7575);
DISPLAY INVISIBLE (-5000 7575);
FORCEPROP 1 LAST PATH I38
J 0
(-5000 7575);
DISPLAY 0.723404 (-5000 7575);
PAINT GREEN (-5000 7575);
DISPLAY INVISIBLE (-5000 7575);
FORCEPROP 1 LAST PART_NUMBER AL008633007
J 0
(-5247 8467);
DISPLAY 0.723404 (-5247 8467);
PAINT GREEN (-5247 8467);
DISPLAY INVISIBLE (-5247 8467);
FORCEADD OFFPAGE..1
(-7450 7750);
PAINT AQUA (-7450 7750);
FORCEPROP 2 LAST $XR3 254 
J 0
(-8062 7750);
DISPLAY 0.638298 (-8062 7750);
PAINT MONO (-8062 7750);
FORCEPROP 2 LAST $XR2 243 
J 0
(-7942 7750);
DISPLAY 0.638298 (-7942 7750);
PAINT MONO (-7942 7750);
FORCEPROP 2 LAST $XR1 268 
J 0
(-7822 7750);
DISPLAY 0.638298 (-7822 7750);
PAINT MONO (-7822 7750);
FORCEPROP 2 LAST $XR0 263 
J 0
(-7702 7750);
DISPLAY 0.638298 (-7702 7750);
PAINT MONO (-7702 7750);
FORCEPROP 2 LAST CDS_LIB standard
J 0
(-7450 7750);
DISPLAY INVISIBLE (-7450 7750);
FORCEPROP 1 LAST OFFPAGE TRUE
J 0
(-7125 7625);
DISPLAY 0.872340 (-7125 7625);
PAINT AQUA (-7125 7625);
DISPLAY INVISIBLE (-7125 7625);
FORCEPROP 1 LAST COMMENT_BODY TRUE
J 0
(-7325 7650);
DISPLAY 0.872340 (-7325 7650);
PAINT GREEN (-7325 7650);
DISPLAY INVISIBLE (-7325 7650);
FORCEPROP 2 LAST PATH I39
J 0
(-7725 7800);
DISPLAY 0.680851 (-7725 7800);
DISPLAY INVISIBLE (-7725 7800);
FORCEADD GND..1
(-6825 6650);
FORCEPROP 3 LASTPIN (-6825 6700) SIG_NAME GND\g
J 0
(-6815 6710);
DISPLAY 0.659574 (-6815 6710);
PAINT MONO (-6815 6710);
DISPLAY INVISIBLE (-6815 6710);
FORCEPROP 2 LAST CDS_LIB pure_quanta_power
J 0
(-6825 6650);
DISPLAY INVISIBLE (-6825 6650);
FORCEPROP 1 LAST SIZE 1B
J 0
(-6750 6600);
DISPLAY 0.872340 (-6750 6600);
PAINT AQUA (-6750 6600);
DISPLAY INVISIBLE (-6750 6600);
FORCEPROP 1 LAST HDL_POWER GND
J 0
(-6825 6800);
DISPLAY 0.872340 (-6825 6800);
PAINT GREEN (-6825 6800);
DISPLAY INVISIBLE (-6825 6800);
FORCEPROP 1 LAST PATH I4
J 0
(-6750 6650);
DISPLAY 0.872340 (-6750 6650);
PAINT AQUA (-6750 6650);
DISPLAY INVISIBLE (-6750 6650);
FORCEADD Q_RES..1
(-6250 7750);
FORCEPROP 1 LAST LOCATION R6097
J 0
(-6475 7775);
DISPLAY 0.638298 (-6475 7775);
FORCEPROP 0 LAST $SEC 1
J 0
(-6125 7825);
DISPLAY 0.680851 (-6125 7825);
PAINT MONO (-6125 7825);
DISPLAY INVISIBLE (-6125 7825);
FORCEPROP 0 LAST CDS_SEC 1
J 0
(-6125 7825);
DISPLAY 1.021277 (-6125 7825);
DISPLAY INVISIBLE (-6125 7825);
FORCEPROP 1 LASTPIN (-6350 7750) $PN 1
J 0
(-6338 7762);
DISPLAY 0.787234 (-6338 7762);
PAINT MONO (-6338 7762);
FORCEPROP 1 LASTPIN (-6150 7750) $PN 2
J 0
(-6188 7762);
DISPLAY 0.787234 (-6188 7762);
PAINT MONO (-6188 7762);
FORCEPROP 1 LAST MATERIAL CHIP
J 0
(-6450 7700);
DISPLAY 0.638298 (-6450 7700);
FORCEPROP 1 LAST VALUE 0
J 2
(-6225 7775);
DISPLAY 0.638298 (-6225 7775);
FORCEPROP 1 LAST WATTAGE 1/16W
J 2
(-6075 7700);
DISPLAY 0.638298 (-6075 7700);
FORCEPROP 1 LAST TOLERANCE 5%
J 0
(-6125 7775);
DISPLAY 0.638298 (-6125 7775);
FORCEPROP 1 LAST PACK_TYPE 0402LF
J 0
(-6450 7650);
DISPLAY 0.638298 (-6450 7650);
FORCEPROP 2 LAST CDS_LIB pure_quanta
J 0
(-6250 7750);
DISPLAY INVISIBLE (-6250 7750);
FORCEPROP 1 LAST PATH I40
J 0
(-6300 7900);
DISPLAY 0.978723 (-6300 7900);
PAINT WHITE (-6300 7900);
DISPLAY INVISIBLE (-6300 7900);
FORCEPROP 1 LAST PART_NUMBER CS00002JB13
J 0
(-6225 7650);
DISPLAY 0.638298 (-6225 7650);
DISPLAY INVISIBLE (-6225 7650);
FORCEADD Q_INDUCTOR..1
(-7925 9150);
FORCEPROP 1 LAST LOCATION PL8064
J 0
(-8050 9310);
DISPLAY 0.617021 (-8050 9310);
PAINT AQUA (-8050 9310);
FORCEPROP 0 LAST $SEC 1
J 0
(-8050 9450);
DISPLAY 0.680851 (-8050 9450);
PAINT MONO (-8050 9450);
DISPLAY INVISIBLE (-8050 9450);
FORCEPROP 0 LAST CDS_SEC 1
J 0
(-8050 9450);
DISPLAY 0.680851 (-8050 9450);
DISPLAY INVISIBLE (-8050 9450);
FORCEPROP 0 LASTPIN (-8025 9125) $PN 1
J 2
(-8035 9135);
DISPLAY 0.617021 (-8035 9135);
PAINT MONO (-8035 9135);
FORCEPROP 0 LASTPIN (-7825 9125) $PN 2
J 0
(-7815 9135);
DISPLAY 0.617021 (-7815 9135);
PAINT MONO (-7815 9135);
FORCEPROP 2 LAST PACK_TYPE SMLF
J 0
(-8050 9400);
DISPLAY 0.617021 (-8050 9400);
PAINT SKYBLUE (-8050 9400);
FORCEPROP 2 LAST VALUE BLM18SN220TN1D/8000MA
J 0
(-8050 9350);
DISPLAY 0.617021 (-8050 9350);
PAINT SKYBLUE (-8050 9350);
FORCEPROP 1 LAST MATERIAL IND
J 0
(-8050 9205);
DISPLAY 0.617021 (-8050 9205);
PAINT SKYBLUE (-8050 9205);
FORCEPROP 1 LAST NEEDS_NO_SIZE TRUE
J 0
(-7925 9150);
DISPLAY 0.468085 (-7925 9150);
PAINT GREEN (-7925 9150);
DISPLAY INVISIBLE (-7925 9150);
FORCEPROP 2 LAST CDS_LIB pure_quanta
J 0
(-7925 9150);
DISPLAY INVISIBLE (-7925 9150);
FORCEPROP 1 LAST PATH I5
J 0
(-7850 9205);
DISPLAY 0.723404 (-7850 9205);
PAINT GREEN (-7850 9205);
DISPLAY INVISIBLE (-7850 9205);
FORCEPROP 1 LAST PART_NUMBER CX220TN1001
J 0
(-8050 9260);
DISPLAY 0.617021 (-8050 9260);
PAINT BLUE (-8050 9260);
DISPLAY INVISIBLE (-8050 9260);
FORCEADD GND..1
(-7425 8525);
FORCEPROP 3 LASTPIN (-7425 8575) SIG_NAME GND\g
J 0
(-7415 8585);
DISPLAY 0.659574 (-7415 8585);
PAINT MONO (-7415 8585);
DISPLAY INVISIBLE (-7415 8585);
FORCEPROP 2 LAST CDS_LIB pure_quanta_power
J 0
(-7425 8525);
DISPLAY INVISIBLE (-7425 8525);
FORCEPROP 1 LAST SIZE 1B
J 0
(-7350 8475);
DISPLAY 0.872340 (-7350 8475);
PAINT AQUA (-7350 8475);
DISPLAY INVISIBLE (-7350 8475);
FORCEPROP 1 LAST HDL_POWER GND
J 0
(-7425 8675);
DISPLAY 0.872340 (-7425 8675);
PAINT GREEN (-7425 8675);
DISPLAY INVISIBLE (-7425 8675);
FORCEPROP 1 LAST PATH I6
J 0
(-7350 8525);
DISPLAY 0.872340 (-7350 8525);
PAINT AQUA (-7350 8525);
DISPLAY INVISIBLE (-7350 8525);
FORCEADD Q_CAP..1
(-7425 8900);
FORCEPROP 1 LAST LOCATION PC1849
J 0
(-7375 9000);
DISPLAY 0.617021 (-7375 9000);
PAINT AQUA (-7375 9000);
FORCEPROP 0 LAST $SEC 1
J 0
(-7375 9050);
DISPLAY 0.680851 (-7375 9050);
PAINT MONO (-7375 9050);
DISPLAY INVISIBLE (-7375 9050);
FORCEPROP 0 LAST CDS_SEC 1
J 0
(-7375 9050);
DISPLAY 1.021277 (-7375 9050);
DISPLAY INVISIBLE (-7375 9050);
FORCEPROP 1 LASTPIN (-7425 9000) $PN 1
J 0
(-7415 8980);
DISPLAY 0.617021 (-7415 8980);
PAINT MONO (-7415 8980);
FORCEPROP 1 LASTPIN (-7425 8800) $PN 2
J 0
(-7415 8780);
DISPLAY 0.617021 (-7415 8780);
PAINT MONO (-7415 8780);
FORCEPROP 1 LAST VALUE 22UF
J 0
(-7375 8950);
DISPLAY 0.617021 (-7375 8950);
PAINT SKYBLUE (-7375 8950);
FORCEPROP 1 LAST PACK_TYPE C0805
J 0
(-7375 8700);
DISPLAY 0.617021 (-7375 8700);
PAINT SKYBLUE (-7375 8700);
FORCEPROP 1 LAST VOLTAGE 16V
J 0
(-7375 8900);
DISPLAY 0.617021 (-7375 8900);
PAINT SKYBLUE (-7375 8900);
FORCEPROP 1 LAST TOLERANCE 20%
J 0
(-7375 8850);
DISPLAY 0.617021 (-7375 8850);
PAINT SKYBLUE (-7375 8850);
FORCEPROP 1 LAST MATERIAL X6S
J 0
(-7375 8800);
DISPLAY 0.617021 (-7375 8800);
PAINT SKYBLUE (-7375 8800);
FORCEPROP 2 LAST CDS_LIB pure_quanta
J 0
(-7425 8900);
DISPLAY INVISIBLE (-7425 8900);
FORCEPROP 1 LAST PATH I7
J 0
(-7375 9050);
DISPLAY 0.978723 (-7375 9050);
PAINT WHITE (-7375 9050);
DISPLAY INVISIBLE (-7375 9050);
FORCEPROP 1 LAST PART_NUMBER CH6223MEA01
J 0
(-7375 8750);
DISPLAY 0.617021 (-7375 8750);
PAINT BLUE (-7375 8750);
DISPLAY INVISIBLE (-7375 8750);
FORCEADD Q_CAP..1
R 2
(-6825 7025);
FORCEPROP 1 LAST LOCATION PC1848
J 2
(-6600 7150);
DISPLAY 0.617021 (-6600 7150);
PAINT AQUA (-6600 7150);
FORCEPROP 2 LAST SEC 1
J 0
(-6875 7221);
DISPLAY 0.680851 (-6875 7221);
PAINT MONO (-6875 7221);
DISPLAY INVISIBLE (-6875 7221);
FORCEPROP 1 LASTPIN (-6825 7125) $PN 1
J 2
(-6779 7096);
DISPLAY 0.617021 (-6779 7096);
FORCEPROP 1 LASTPIN (-6825 6925) $PN 2
J 2
(-6781 6920);
DISPLAY 0.617021 (-6781 6920);
FORCEPROP 1 LAST VALUE 1UF
J 0
(-6725 7095);
DISPLAY 0.617021 (-6725 7095);
PAINT SKYBLUE (-6725 7095);
FORCEPROP 1 LAST TOLERANCE 10%
J 0
(-6725 6997);
DISPLAY 0.617021 (-6725 6997);
PAINT SKYBLUE (-6725 6997);
FORCEPROP 1 LAST MATERIAL X6S
J 0
(-6725 6948);
DISPLAY 0.617021 (-6725 6948);
PAINT SKYBLUE (-6725 6948);
FORCEPROP 1 LAST PACK_TYPE C0402
J 0
(-6725 6899);
DISPLAY 0.617021 (-6725 6899);
PAINT SKYBLUE (-6725 6899);
FORCEPROP 1 LAST VOLTAGE 25V
J 0
(-6725 7046);
DISPLAY 0.617021 (-6725 7046);
PAINT SKYBLUE (-6725 7046);
FORCEPROP 2 LAST CDS_LIB pure_quanta
J 0
(-6825 7025);
DISPLAY INVISIBLE (-6825 7025);
FORCEPROP 2 LAST SIGNAL_MODEL DEFAULT_CAPACITOR_100000PF_2_1
R 3
J 1
(-6895 6973);
DISPLAY 0.744681 (-6895 6973);
PAINT MONO (-6895 6973);
DISPLAY INVISIBLE (-6895 6973);
FORCEPROP 2 LAST SEC_TYPE C0402
J 0
(-6875 7221);
DISPLAY 1.021277 (-6875 7221);
DISPLAY INVISIBLE (-6875 7221);
FORCEPROP 1 LAST PATH I8
J 2
(-6875 7175);
DISPLAY 0.978723 (-6875 7175);
PAINT WHITE (-6875 7175);
DISPLAY INVISIBLE (-6875 7175);
FORCEPROP 1 LAST PART_NUMBER CH5104KEB02
J 0
(-6725 6850);
DISPLAY 0.617021 (-6725 6850);
PAINT BLUE (-6725 6850);
DISPLAY INVISIBLE (-6725 6850);
FORCEADD UNIVERSAL_POWER..1
(-6825 7525);
FORCEPROP 3 LASTPIN (-6825 7475) SIG_NAME P5V_AUX_VCC\g
J 0
(-6815 7485);
DISPLAY 0.659574 (-6815 7485);
PAINT MONO (-6815 7485);
DISPLAY INVISIBLE (-6815 7485);
FORCEPROP 1 LAST HDL_POWER P5V_AUX_VCC
J 1
(-6825 7575);
DISPLAY 0.617021 (-6825 7575);
PAINT GREEN (-6825 7575);
FORCEPROP 2 LAST CDS_LIB pure_quanta_power
J 0
(-6825 7525);
PAINT MONO (-6825 7525);
DISPLAY INVISIBLE (-6825 7525);
FORCEPROP 1 LAST PATH I9
J 0
(-6775 7550);
DISPLAY 0.872340 (-6775 7550);
PAINT AQUA (-6775 7550);
DISPLAY INVISIBLE (-6775 7550);
FORCEADD QUANTA_TITLE_BLOCK_C..1
(750 4075);
FORCEPROP 0 LAST CDS_CON_LAST_MODIFIED Thu Sep 14 16:12:40 2023
J 0
(-1135 4090);
DISPLAY INVISIBLE (-1135 4090);
FORCEPROP 1 LAST CUSTOM_TXT_CDS <CON_LAST_MODIFIED>
J 0
(-1135 4090);
DISPLAY 0.978723 (-1135 4090);
FORCEPROP 2 LAST CUSTOM_TXT_CDS <XR_PAGE_TITLE>
J 0
(-7140 9325);
DISPLAY 0.638298 (-7140 9325);
PAINT PINK (-7140 9325);
DISPLAY INVISIBLE (-7140 9325);
FORCEPROP 1 LAST CUSTOM_TXT_CDS <NAME_2>
J 0
(-2425 4125);
FORCEPROP 1 LAST CUSTOM_TXT_CDS <NAME_1>
J 0
(-2425 4250);
FORCEPROP 1 LAST CUSTOM_TXT_CDS <Q_NUMBER>
J 0
(-653 4178);
DISPLAY 1.212766 (-653 4178);
FORCEPROP 1 LAST CUSTOM_TXT_CDS <Q_PROJ>
J 0
(-1632 4177);
DISPLAY 1.212766 (-1632 4177);
FORCEPROP 1 LAST CUSTOM_TXT_CDS <Q_REV>
J 0
(566 4178);
DISPLAY 1.212766 (566 4178);
FORCEPROP 1 LAST CUSTOM_TXT_CDS <CON_PAGE_NUM> OF <CON_TOTAL_PAGES>
J 0
(304 4093);
DISPLAY 0.978723 (304 4093);
FORCEPROP 1 LAST Q_TITLE MPQ8633A/P5V_AUX
J 0
(-8525 4125);
DISPLAY 2.446809 (-8525 4125);
PAINT GREEN (-8525 4125);
FORCEPROP 2 LAST PAGE_BORDER TRUE
J 0
(-7140 9325);
DISPLAY 0.638298 (-7140 9325);
PAINT PINK (-7140 9325);
DISPLAY INVISIBLE (-7140 9325);
FORCEPROP 1 LAST CDS_LMAN_SYM_OUTLINE -9475,6775,100,-125
J 0
(750 4075);
DISPLAY 0.468085 (750 4075);
PAINT GREEN (750 4075);
DISPLAY INVISIBLE (750 4075);
FORCEPROP 2 LAST CDS_LIB pure_quanta
J 0
(750 4075);
DISPLAY INVISIBLE (750 4075);
FORCEPROP 2 LAST CDS_XR_PAGE_TITLE CR-189 : @T6G_MB_LIB.T6G(SCH_1):PAGE189
J 0
(-7140 9325);
DISPLAY 0.638298 (-7140 9325);
PAINT PINK (-7140 9325);
DISPLAY INVISIBLE (-7140 9325);
FORCEPROP 1 LAST Q_DEPT BU9
J 1
(-3013 4124);
DISPLAY 1.957447 (-3013 4124);
PAINT GREEN (-3013 4124);
DISPLAY INVISIBLE (-3013 4124);
FORCEPROP 1 LAST COMMENT_BODY TRUE
J 0
(762 4062);
DISPLAY 0.978723 (762 4062);
PAINT GREEN (762 4062);
DISPLAY INVISIBLE (762 4062);
WIRE 16 -1 (-8200 8725)(-8200 8825);
WIRE 16 -1 (-5887 6493)(-5887 6632);
WIRE 16 -1 (-4250 6675)(-4250 6750);
WIRE 16 -1 (-5875 7450)(-5575 7450);
WIRE 16 -1 (-5575 7450)(-5575 7425);
WIRE 16 -1 (-3675 6925)(-3675 6750);
WIRE 16 -1 (-3725 8875)(-3725 8725);
FORCEPROP 2 LAST SIG_NAME P5V_AUX_VCC\G
J 0
(-3715 8885);
DISPLAY 0.659574 (-3715 8885);
DISPLAY INVISIBLE (-3715 8885);
FORCEPROP 2 LASTPROP $XRERR UNIQUE?
J 0
(-3955 8885);
DISPLAY 0.638298 (-3955 8885);
PAINT MONO (-3955 8885);
DISPLAY INVISIBLE (-3955 8885);
WIRE 16 -1 (-6825 6700)(-6825 6925);
WIRE 16 2175 (-8375 5450)(-6450 5450);
WIRE 16 2175 (-8375 5450)(-8375 5100);
WIRE 16 2175 (-6450 5450)(-6450 5100);
WIRE 16 2175 (-8375 5100)(-6450 5100);
WIRE 16 2175 (-8375 5000)(-6772 5000);
WIRE 16 2175 (-8375 5000)(-8375 4475);
WIRE 16 2175 (-6772 5000)(-6772 4475);
WIRE 16 2175 (-8375 4475)(-6772 4475);
WIRE 16 -1 (-2925 7300)(-2925 6950);
WIRE 16 -1 (-2925 7300)(-3675 7300);
WIRE 16 -1 (-2400 6950)(-2925 6950);
WIRE 16 -1 (-2925 6950)(-2925 6625);
WIRE 16 -1 (-2425 6625)(-2925 6625);
WIRE 16 -1 (-3675 7125)(-3675 7300);
WIRE 16 -1 (-4600 7300)(-3675 7300);
FORCEPROP 2 LAST SIG_NAME P5V_AUX_FB
J 0
(-4510 7310);
DISPLAY 0.617021 (-4510 7310);
FORCEPROP 2 LASTPROP $XRERR UNIQUE?
J 0
(-4750 7310);
DISPLAY 0.638298 (-4750 7310);
PAINT MONO (-4750 7310);
DISPLAY INVISIBLE (-4750 7310);
WIRE 16 -1 (-5575 9125)(-5575 8250);
WIRE 16 -1 (-6175 9125)(-5575 9125);
WIRE 16 -1 (-5575 8250)(-5400 8250);
WIRE 16 -1 (-5575 8250)(-5575 8200);
WIRE 16 -1 (-5575 8200)(-5400 8200);
WIRE 16 -1 (-6175 9000)(-6175 9125);
WIRE 16 -1 (-6575 9125)(-6175 9125);
WIRE 16 -1 (-6575 9000)(-6575 9125);
WIRE 16 -1 (-7025 9125)(-6575 9125);
WIRE 16 -1 (-7025 9000)(-7025 9125);
WIRE 16 -1 (-7425 9125)(-7025 9125);
FORCEPROP 2 LAST SIG_NAME SW_P5V_AUX_FLT
J 0
(-6035 9135);
DISPLAY 0.617021 (-6035 9135);
FORCEPROP 2 LASTPROP $XRERR UNIQUE?
J 0
(-6275 9135);
DISPLAY 0.638298 (-6275 9135);
PAINT MONO (-6275 9135);
DISPLAY INVISIBLE (-6275 9135);
WIRE 16 -1 (-7425 9000)(-7425 9125);
WIRE 16 -1 (-7825 9125)(-7425 9125);
WIRE 16 -1 (-6175 8800)(-6175 8678);
WIRE 16 -1 (-6175 8678)(-6575 8678);
WIRE 16 -1 (-6575 8800)(-6575 8678);
WIRE 16 -1 (-6575 8678)(-7025 8678);
WIRE 16 -1 (-7025 8800)(-7025 8678);
WIRE 16 -1 (-7425 8678)(-7025 8678);
WIRE 16 -1 (-7425 8800)(-7425 8678);
WIRE 16 -1 (-7425 8575)(-7425 8678);
WIRE 16 -1 (-6825 7300)(-5400 7300);
WIRE 16 -1 (-6825 7475)(-6825 7300);
WIRE 16 -1 (-6825 7125)(-6825 7300);
WIRE 16 -1 (-4375 6900)(-4375 6950);
WIRE 16 -1 (-4600 6900)(-4375 6900);
WIRE 16 -1 (-4375 6675)(-4375 6900);
WIRE 16 -1 (-4375 6950)(-4600 6950);
WIRE 16 -1 (-2125 8250)(-3050 8250);
FORCEPROP 2 LAST SIG_NAME PWRGD_P5V_AUX
J 0
(-2660 8260);
DISPLAY 0.617021 (-2660 8260);
WIRE 16 3135 (-675 10000)(600 10000);
WIRE 16 3135 (-675 10000)(-675 10600);
WIRE 16 3135 (600 10600)(600 10000);
WIRE 16 3135 (-675 10600)(600 10600);
WIRE 16 -1 (-3725 7800)(-3725 7750);
WIRE 16 -1 (-3725 7750)(-2925 7750);
WIRE 16 -1 (-4600 7750)(-3725 7750);
FORCEPROP 2 LAST SIG_NAME SW_P5V_AUX_SW
J 0
(-4510 7760);
DISPLAY 0.617021 (-4510 7760);
FORCEPROP 2 LASTPROP $XRERR UNIQUE?
J 0
(-4750 7760);
DISPLAY 0.638298 (-4750 7760);
PAINT MONO (-4750 7760);
DISPLAY INVISIBLE (-4750 7760);
WIRE 16 -1 (-7400 7750)(-6350 7750);
FORCEPROP 2 LAST SIG_NAME MB0_P12V_STBY_PWRGD
J 0
(-7260 7760);
DISPLAY 0.638298 (-7260 7760);
WIRE 16 -1 (-6150 7750)(-5400 7750);
FORCEPROP 2 LAST SIG_NAME P5V_AUX_EN
J 0
(-5935 7760);
DISPLAY 0.617021 (-5935 7760);
FORCEPROP 2 LASTPROP $XRERR UNIQUE?
J 0
(-6175 7760);
DISPLAY 0.638298 (-6175 7760);
PAINT MONO (-6175 7760);
DISPLAY INVISIBLE (-6175 7760);
WIRE 16 -1 (-5400 7550)(-6325 7550);
FORCEPROP 2 LAST SIG_NAME P5V_AUX_MODE
J 0
(-6010 7560);
DISPLAY 0.638298 (-6010 7560);
FORCEPROP 2 LASTPROP $XRERR UNIQUE?
J 0
(-6250 7560);
DISPLAY 0.638298 (-6250 7560);
PAINT MONO (-6250 7560);
DISPLAY INVISIBLE (-6250 7560);
WIRE 16 -1 (-6325 7550)(-6325 7450);
WIRE 16 -1 (-6325 7450)(-6075 7450);
WIRE 16 -1 (-5887 6950)(-5400 6950);
WIRE 16 -1 (-5887 6832)(-5887 6950);
FORCEPROP 2 LAST SIG_NAME P5V_AUX_CS
J 0
(-6010 6960);
DISPLAY 0.617021 (-6010 6960);
FORCEPROP 2 LASTPROP $XRERR UNIQUE?
J 0
(-6250 6960);
DISPLAY 0.638298 (-6250 6960);
PAINT MONO (-6250 6960);
DISPLAY INVISIBLE (-6250 6960);
WIRE 16 -1 (-4600 7050)(-4250 7050);
FORCEPROP 2 LAST SIG_NAME P5V_AUX_REF
J 0
(-4510 7060);
DISPLAY 0.617021 (-4510 7060);
FORCEPROP 2 LASTPROP $XRERR UNIQUE?
J 0
(-4750 7060);
DISPLAY 0.638298 (-4750 7060);
PAINT MONO (-4750 7060);
DISPLAY INVISIBLE (-4750 7060);
WIRE 16 -1 (-4250 7050)(-4250 6950);
WIRE 16 -1 (-4600 8050)(-3725 8050);
FORCEPROP 2 LAST SIG_NAME SW_P5V_AUX_BST
J 0
(-4510 8060);
DISPLAY 0.617021 (-4510 8060);
FORCEPROP 2 LASTPROP $XRERR UNIQUE?
J 0
(-4750 8060);
DISPLAY 0.638298 (-4750 8060);
PAINT MONO (-4750 8060);
DISPLAY INVISIBLE (-4750 8060);
WIRE 16 -1 (-3725 8000)(-3725 8050);
WIRE 16 -1 (-2757 6422)(-2757 6423);
WIRE 16 -1 (-1044 7126)(-1044 7127);
WIRE 16 -1 (-3250 8250)(-3725 8250);
WIRE 16 -1 (-3725 8525)(-3725 8250);
WIRE 16 -1 (-3725 8250)(-4600 8250);
FORCEPROP 2 LAST SIG_NAME PWRGD_P5V_AUX_R
J 0
(-4510 8260);
DISPLAY 0.617021 (-4510 8260);
FORCEPROP 2 LASTPROP $XRERR UNIQUE?
J 0
(-4750 8260);
DISPLAY 0.638298 (-4750 8260);
PAINT MONO (-4750 8260);
DISPLAY INVISIBLE (-4750 8260);
WIRE 16 -1 (-8200 9025)(-8200 9125);
WIRE 16 -1 (-8200 9125)(-8196 9125);
WIRE 16 -1 (-8025 9125)(-8196 9125);
WIRE 16 -1 (-8196 9295)(-8196 9125);
WIRE 16 -1 (-1375 6625)(-1375 6950);
WIRE 16 -1 (-1375 6625)(-2225 6625);
WIRE 16 -1 (325 6950)(-1375 6950);
WIRE 16 -1 (-2200 6950)(-1375 6950);
WIRE 16 -1 (325 7750)(325 6950);
WIRE 16 -1 (325 7750)(-175 7750);
WIRE 16 -1 (325 7750)(325 8175);
WIRE 16 -1 (-175 7600)(-175 7750);
WIRE 16 -1 (-175 7750)(-600 7750);
WIRE 16 -1 (-600 7750)(-600 7600);
WIRE 16 -1 (-600 7750)(-1100 7750);
WIRE 16 -1 (-1100 7750)(-1100 7600);
WIRE 16 -1 (-1550 7750)(-1100 7750);
WIRE 16 -1 (-1550 7600)(-1550 7750);
WIRE 16 -1 (-2725 7750)(-1550 7750);
WIRE 16 -1 (-175 7400)(-175 7250);
WIRE 16 -1 (-175 7250)(-600 7250);
WIRE 16 -1 (-175 7150)(-175 7250);
WIRE 16 -1 (-600 7400)(-600 7250);
WIRE 16 -1 (-600 7250)(-1100 7250);
WIRE 16 -1 (-1100 7400)(-1100 7250);
WIRE 16 -1 (-1100 7250)(-1550 7250);
WIRE 16 -1 (-1550 7400)(-1550 7250);
WIRE 16 -1 (-3825 6750)(-3825 7150);
WIRE 16 -1 (-3825 7150)(-4600 7150);
CIRCLE (-6625 8000)(-6395 8000);
PAINT YELLOW (-6625 8000);
DOT 1 (-7425 8678);
DOT 1 (-7025 8678);
DOT 1 (-6575 8678);
DOT 1 (-8196 9125);
DOT 1 (-7425 9125);
DOT 1 (-7025 9125);
DOT 1 (-6575 9125);
DOT 1 (-6175 9125);
DOT 1 (-6825 7300);
DOT 1 (325 7750);
DOT 1 (-175 7750);
DOT 1 (-600 7750);
DOT 1 (-175 7250);
DOT 1 (-600 7250);
DOT 1 (-1100 7750);
DOT 1 (-1550 7750);
DOT 1 (-1100 7250);
DOT 1 (-1375 6950);
DOT 1 (-2925 6950);
DOT 1 (-3725 8250);
DOT 1 (-3725 7750);
DOT 1 (-3675 7300);
DOT 1 (-4375 6900);
DOT 1 (-5575 8250);
FORCENOTE
1ST AL008633007/MPQ8633AGLE-C807-Z/MPS
(-8325 5250) 0;
DISPLAY LEFT (-8325 5250);
DISPLAY 1.021277 (-8325 5250);
PAINT WHITE (-8325 5250);
FORCENOTE
2ND AL053318002/RS53318LR/REEDSEMI
(-8325 5184) 0;
DISPLAY LEFT (-8325 5184);
DISPLAY 1.021277 (-8325 5184);
PAINT WHITE (-8325 5184);
FORCENOTE
3RD AL000548006/TPS548A28RWWR/TI
(-8325 5125) 0;
DISPLAY LEFT (-8325 5125);
DISPLAY 1.021277 (-8325 5125);
PAINT WHITE (-8325 5125);
FORCENOTE
BOM CHANGE R&C TABLE
(-8350 4900) 0;
DISPLAY LEFT (-8350 4900);
DISPLAY 1.170213 (-8350 4900);
PAINT WHITE (-8350 4900);
FORCENOTE
PC1848 CHANGE TO CH5222KEB01
(-8125 4675) 0;
DISPLAY LEFT (-8125 4675);
DISPLAY 1.021277 (-8125 4675);
PAINT WHITE (-8125 4675);
FORCENOTE
PC1877 CHANGE TO CH1156F0B00
(-8125 4600) 0;
DISPLAY LEFT (-8125 4600);
DISPLAY 1.021277 (-8125 4600);
PAINT WHITE (-8125 4600);
FORCENOTE
PR8089 CHANGE TO CS31402FB03
(-8125 4525) 0;
DISPLAY LEFT (-8125 4525);
DISPLAY 1.021277 (-8125 4525);
PAINT WHITE (-8125 4525);
FORCENOTE
DCR=15MOHM
(-3025 7500) 0;
DISPLAY LEFT (-3025 7500);
DISPLAY 1.021277 (-3025 7500);
FORCENOTE
3RD 
(-8350 4675) 0;
DISPLAY LEFT (-8350 4675);
DISPLAY 1.170213 (-8350 4675);
PAINT WHITE (-8350 4675);
FORCENOTE
1ST 
(-8350 4825) 0;
DISPLAY LEFT (-8350 4825);
DISPLAY 1.170213 (-8350 4825);
PAINT WHITE (-8350 4825);
FORCENOTE
2ND NA
(-8350 4750) 0;
DISPLAY LEFT (-8350 4750);
DISPLAY 1.170213 (-8350 4750);
PAINT WHITE (-8350 4750);
FORCENOTE
WORK FREQUENCY = 600KHZ
(-650 10025) 0;
DISPLAY LEFT (-650 10025);
DISPLAY 0.808511 (-650 10025);
PAINT WHITE (-650 10025);
FORCENOTE
SLEW RATE = 1A/US
(-650 10075) 0;
DISPLAY LEFT (-650 10075);
DISPLAY 0.808511 (-650 10075);
PAINT WHITE (-650 10075);
FORCENOTE
CURRENT STEP = 1A
(-650 10125) 0;
DISPLAY LEFT (-650 10125);
DISPLAY 0.808511 (-650 10125);
PAINT WHITE (-650 10125);
FORCENOTE
OCP(IMAX*120%) = 4A
(-650 10175) 0;
DISPLAY LEFT (-650 10175);
DISPLAY 0.808511 (-650 10175);
PAINT RED (-650 10175);
FORCENOTE
TDC = 1.8A
(-650 10275) 0;
DISPLAY LEFT (-650 10275);
DISPLAY 0.808511 (-650 10275);
PAINT RED (-650 10275);
FORCENOTE
IMAX = 2.1A
(-650 10225) 0;
DISPLAY LEFT (-650 10225);
DISPLAY 0.808511 (-650 10225);
PAINT RED (-650 10225);
FORCENOTE
DESIGN SPECIFICATION
(-650 10550) 0;
DISPLAY LEFT (-650 10550);
DISPLAY 0.808511 (-650 10550);
PAINT WHITE (-650 10550);
FORCENOTE
OUTPUT VOLTAGE = 5.0V
(-650 10475) 0;
DISPLAY LEFT (-650 10475);
DISPLAY 0.808511 (-650 10475);
PAINT WHITE (-650 10475);
FORCENOTE
DC TOLERANCE = +/-1.5%
(-650 10425) 0;
DISPLAY LEFT (-650 10425);
DISPLAY 0.808511 (-650 10425);
PAINT WHITE (-650 10425);
FORCENOTE
OUTPUT RIPPLE & NOISE = +/-1.0%
(-650 10375) 0;
DISPLAY LEFT (-650 10375);
DISPLAY 0.808511 (-650 10375);
PAINT WHITE (-650 10375);
FORCENOTE
TRANSIENT TOLERANCE = +/-5.0%
(-650 10325) 0;
DISPLAY LEFT (-650 10325);
DISPLAY 0.808511 (-650 10325);
PAINT WHITE (-650 10325);
FORCENOTE
TBC
(-6650 7975) 0;
DISPLAY LEFT (-6650 7975);
DISPLAY 1.021277 (-6650 7975);
FORCENOTE
PCMB104E-4R7MS
(-3025 7650) 0;
DISPLAY LEFT (-3025 7650);
DISPLAY 1.021277 (-3025 7650);
FORCENOTE
10.3*11.2*4.0
(-3025 7600) 0;
DISPLAY LEFT (-3025 7600);
DISPLAY 1.021277 (-3025 7600);
FORCENOTE
ISAT=13A
(-3025 7550) 0;
DISPLAY LEFT (-3025 7550);
DISPLAY 1.021277 (-3025 7550);
FORCENOTE
P5V_AUX
(-5775 9625) 0;
DISPLAY LEFT (-5775 9625);
DISPLAY 4.914894 (-5775 9625);
PAINT YELLOW (-5775 9625);
FORCENOTE
VOUT=0.6(1+RA/RB)=5.003V
(-3470 6101) 0;
DISPLAY LEFT (-3470 6101);
DISPLAY 2.000000 (-3470 6101);
PAINT SKYBLUE (-3470 6101);
FORCENOTE
RA
(-2350 7025) 0;
DISPLAY LEFT (-2350 7025);
DISPLAY 1.021277 (-2350 7025);
FORCENOTE
RB
(-3600 7225) 0;
DISPLAY LEFT (-3600 7225);
DISPLAY 1.021277 (-3600 7225);
FORCENOTE
BOM NOTE
(-8350 5350) 0;
DISPLAY LEFT (-8350 5350);
DISPLAY 1.170213 (-8350 5350);
PAINT WHITE (-8350 5350);
QUIT
